(kicad_pcb
	(version 20260206)
	(generator "pcbnew")
	(generator_version "10.0")
	(general
		(thickness 1.6)
		(legacy_teardrops no)
	)
	(paper "A4")
	(title_block
		(title "12092022_DA0F0TMDCD0_F0T_Management_Board_D_brd_V3_OCP.brd")
		(comment 1 "Grand Teton / footprints 348-354 of 1440")
	)
	(layers
		(0 "F.Cu" signal "TOP")
		(4 "In1.Cu" signal "GND")
		(6 "In2.Cu" signal "IN1")
		(8 "In3.Cu" signal "GND1")
		(10 "In4.Cu" signal "IN2")
		(12 "In5.Cu" signal "VCC")
		(14 "In6.Cu" signal "VCC1")
		(16 "In7.Cu" signal "IN3")
		(18 "In8.Cu" signal "GND2")
		(20 "In9.Cu" signal "IN4")
		(22 "In10.Cu" signal "GND3")
		(2 "B.Cu" signal "BOTTOM")
		(9 "F.Adhes" user "F.Adhesive")
		(11 "B.Adhes" user "B.Adhesive")
		(13 "F.Paste" user "Package Geometry/Pastemask Top")
		(15 "B.Paste" user "Package Geometry/Pastemask Bottom")
		(5 "F.SilkS" user "Ref Des/Silkscreen Top")
		(7 "B.SilkS" user "Ref Des/Silkscreen Bottom")
		(1 "F.Mask" user "Board Geometry/Soldermask Top")
		(3 "B.Mask" user "Board Geometry/Soldermask Bottom")
		(17 "Dwgs.User" user "User.Drawings")
		(19 "Cmts.User" user "User.Comments")
		(21 "Eco1.User" user "User.Eco1")
		(23 "Eco2.User" user "User.Eco2")
		(25 "Edge.Cuts" user "Board Geometry/Outline")
		(27 "Margin" user)
		(31 "F.CrtYd" user "Package Geometry/Place Bound Top")
		(29 "B.CrtYd" user "Package Geometry/Place Bound Bottom")
		(35 "F.Fab" user "Ref Des/Assembly Top")
		(33 "B.Fab" user "Ref Des/Assembly Bottom")
	)
	(footprint ""
		(layer "F.Cu")
		(at 50.64887 -109.411008 90)
		(property "Reference" "R103"
			(at 0 0 90)
			(layer "F.SilkS")
			(hide yes)
			(effects
				(font
					(size 1.27 1.27)
				)
			)
		)
		(property "Value" ""
			(at 0 0 90)
			(layer "F.Fab")
			(effects
				(font
					(size 1.27 1.27)
				)
			)
		)
		(duplicate_pad_numbers_are_jumpers no)
		(fp_line
			(start 0.7874 -0.4064)
			(end 0.7874 0.4064)
			(stroke
				(width 0.1524)
				(type default)
			)
			(layer "F.SilkS")
		)
		(fp_line
			(start -0.7874 -0.4064)
			(end 0.7874 -0.4064)
			(stroke
				(width 0.1524)
				(type default)
			)
			(layer "F.SilkS")
		)
		(fp_line
			(start 0.7874 0.4064)
			(end -0.7874 0.4064)
			(stroke
				(width 0.1524)
				(type default)
			)
			(layer "F.SilkS")
		)
		(fp_line
			(start -0.7874 0.4064)
			(end -0.7874 -0.4064)
			(stroke
				(width 0.1524)
				(type default)
			)
			(layer "F.SilkS")
		)
		(fp_line
			(start -0.12065 -0.305054)
			(end -0.12065 -0.2794)
			(stroke
				(width 0.1)
				(type default)
			)
			(layer "F.Fab")
		)
		(fp_line
			(start -0.67945 -0.305054)
			(end -0.12065 -0.305054)
			(stroke
				(width 0.1)
				(type default)
			)
			(layer "F.Fab")
		)
		(fp_line
			(start 0.67945 -0.3048)
			(end 0.67945 0.3048)
			(stroke
				(width 0.1)
				(type default)
			)
			(layer "F.Fab")
		)
		(fp_line
			(start 0.12065 -0.3048)
			(end 0.67945 -0.3048)
			(stroke
				(width 0.1)
				(type default)
			)
			(layer "F.Fab")
		)
		(fp_line
			(start 0.12065 -0.2794)
			(end 0.12065 -0.3048)
			(stroke
				(width 0.1)
				(type default)
			)
			(layer "F.Fab")
		)
		(fp_line
			(start -0.12065 -0.2794)
			(end 0.12065 -0.2794)
			(stroke
				(width 0.1)
				(type default)
			)
			(layer "F.Fab")
		)
		(fp_line
			(start 0.120396 0.2794)
			(end -0.12065 0.2794)
			(stroke
				(width 0.1)
				(type default)
			)
			(layer "F.Fab")
		)
		(fp_line
			(start -0.12065 0.2794)
			(end -0.12065 0.3048)
			(stroke
				(width 0.1)
				(type default)
			)
			(layer "F.Fab")
		)
		(fp_line
			(start 0.67945 0.3048)
			(end 0.120396 0.3048)
			(stroke
				(width 0.1)
				(type default)
			)
			(layer "F.Fab")
		)
		(fp_line
			(start 0.120396 0.3048)
			(end 0.120396 0.2794)
			(stroke
				(width 0.1)
				(type default)
			)
			(layer "F.Fab")
		)
		(fp_line
			(start -0.12065 0.3048)
			(end -0.67945 0.3048)
			(stroke
				(width 0.1)
				(type default)
			)
			(layer "F.Fab")
		)
		(fp_line
			(start -0.67945 0.3048)
			(end -0.67945 -0.305054)
			(stroke
				(width 0.1)
				(type default)
			)
			(layer "F.Fab")
		)
		(pad "1" smd circle
			(at -0.40005 0 90)
			(size 0 0)
			(layers "F.Cu" "F.Mask" "F.Paste")
			(net "P3V3_AUX")
		)
		(pad "2" smd circle
			(at 0.40005 0 90)
			(size 0 0)
			(layers "F.Cu" "F.Mask" "F.Paste")
			(net "RMII_TXEN")
		)
	)
	(footprint ""
		(layer "F.Cu")
		(at 53.630068 -6.290056)
		(property "Reference" "D21"
			(at -1.143 -2.708148 0)
			(unlocked yes)
			(layer "F.SilkS")
			(effects
				(font
					(size 0.7874 0.5842)
					(thickness 0.1524)
				)
				(justify left)
			)
		)
		(property "Value" ""
			(at 0 0 0)
			(layer "F.Fab")
			(effects
				(font
					(size 1.27 1.27)
				)
			)
		)
		(duplicate_pad_numbers_are_jumpers no)
		(fp_line
			(start -1.080008 -1.999996)
			(end 3.620008 -1.999996)
			(stroke
				(width 0.1524)
				(type default)
			)
			(layer "F.SilkS")
		)
		(fp_line
			(start -1.080008 3.999992)
			(end -1.080008 -1.999996)
			(stroke
				(width 0.1524)
				(type default)
			)
			(layer "F.SilkS")
		)
		(fp_line
			(start -0.230124 3.999992)
			(end -1.080008 3.999992)
			(stroke
				(width 0.1524)
				(type default)
			)
			(layer "F.SilkS")
		)
		(fp_line
			(start -0.230124 5.199888)
			(end -0.230124 3.999992)
			(stroke
				(width 0.1524)
				(type default)
			)
			(layer "F.SilkS")
		)
		(fp_line
			(start 2.770124 3.999992)
			(end 2.770124 5.199888)
			(stroke
				(width 0.1524)
				(type default)
			)
			(layer "F.SilkS")
		)
		(fp_line
			(start 3.620008 -1.999996)
			(end 3.620008 3.999992)
			(stroke
				(width 0.1524)
				(type default)
			)
			(layer "F.SilkS")
		)
		(fp_line
			(start 3.620008 3.999992)
			(end 2.770124 3.999992)
			(stroke
				(width 0.1524)
				(type default)
			)
			(layer "F.SilkS")
		)
		(fp_arc
			(start 1.27 6.700012)
			(mid 0.209252 6.260636)
			(end -0.230124 5.199888)
			(stroke
				(width 0.1524)
				(type default)
			)
			(layer "F.SilkS")
		)
		(fp_arc
			(start 2.770124 5.199888)
			(mid 2.330748 6.260636)
			(end 1.27 6.700012)
			(stroke
				(width 0.1524)
				(type default)
			)
			(layer "F.SilkS")
		)
		(fp_line
			(start -1.080008 -1.999996)
			(end 3.620008 -1.999996)
			(stroke
				(width 0.1)
				(type default)
			)
			(layer "F.Fab")
		)
		(fp_line
			(start -1.080008 3.999992)
			(end -1.080008 -1.999996)
			(stroke
				(width 0.1)
				(type default)
			)
			(layer "F.Fab")
		)
		(fp_line
			(start -0.230124 3.999992)
			(end -1.080008 3.999992)
			(stroke
				(width 0.1)
				(type default)
			)
			(layer "F.Fab")
		)
		(fp_line
			(start -0.230124 5.199888)
			(end -0.230124 3.999992)
			(stroke
				(width 0.1)
				(type default)
			)
			(layer "F.Fab")
		)
		(fp_line
			(start 2.770124 3.999992)
			(end 2.770124 5.199888)
			(stroke
				(width 0.1)
				(type default)
			)
			(layer "F.Fab")
		)
		(fp_line
			(start 3.620008 -1.999996)
			(end 3.620008 3.999992)
			(stroke
				(width 0.1)
				(type default)
			)
			(layer "F.Fab")
		)
		(fp_line
			(start 3.620008 3.999992)
			(end 2.770124 3.999992)
			(stroke
				(width 0.1)
				(type default)
			)
			(layer "F.Fab")
		)
		(fp_arc
			(start 1.27 6.700012)
			(mid 0.209252 6.260636)
			(end -0.230124 5.199888)
			(stroke
				(width 0.1)
				(type default)
			)
			(layer "F.Fab")
		)
		(fp_arc
			(start 2.770124 5.199888)
			(mid 2.330748 6.260636)
			(end 1.27 6.700012)
			(stroke
				(width 0.1)
				(type default)
			)
			(layer "F.Fab")
		)
		(pad "A" thru_hole rect
			(at 0 0)
			(size 1.2192 1.2192)
			(drill 0.8128)
			(layers "*.Cu" "*.Mask")
			(remove_unused_layers no)
			(net "LED_D21_R3")
			(clearance 0.0508)
			(thermal_gap 0.0508)
			(padstack
				(mode front_inner_back)
				(layer "Inner"
					(shape circle)
					(size 1.2192 1.2192)
					(clearance 0.0508)
				)
				(layer "B.Cu"
					(shape rect)
					(size 1.2192 1.2192)
					(clearance 0.0508)
				)
			)
		)
		(pad "C" thru_hole circle
			(at 2.54 0)
			(size 1.2192 1.2192)
			(drill 0.8128)
			(layers "*.Cu" "*.Mask")
			(remove_unused_layers no)
			(net "GND")
			(clearance 0.0508)
			(thermal_gap 0.0508)
		)
	)
	(footprint ""
		(layer "F.Cu")
		(at 56.4642 -71.2724 90)
		(property "Reference" "R466"
			(at 0 0 90)
			(layer "F.SilkS")
			(hide yes)
			(effects
				(font
					(size 1.27 1.27)
				)
			)
		)
		(property "Value" ""
			(at 0 0 90)
			(layer "F.Fab")
			(effects
				(font
					(size 1.27 1.27)
				)
			)
		)
		(duplicate_pad_numbers_are_jumpers no)
		(fp_line
			(start 0.7874 -0.4064)
			(end 0.7874 0.4064)
			(stroke
				(width 0.1524)
				(type default)
			)
			(layer "F.SilkS")
		)
		(fp_line
			(start -0.7874 -0.4064)
			(end 0.7874 -0.4064)
			(stroke
				(width 0.1524)
				(type default)
			)
			(layer "F.SilkS")
		)
		(fp_line
			(start 0.7874 0.4064)
			(end -0.7874 0.4064)
			(stroke
				(width 0.1524)
				(type default)
			)
			(layer "F.SilkS")
		)
		(fp_line
			(start -0.7874 0.4064)
			(end -0.7874 -0.4064)
			(stroke
				(width 0.1524)
				(type default)
			)
			(layer "F.SilkS")
		)
		(fp_line
			(start -0.12065 -0.305054)
			(end -0.12065 -0.2794)
			(stroke
				(width 0.1)
				(type default)
			)
			(layer "F.Fab")
		)
		(fp_line
			(start -0.67945 -0.305054)
			(end -0.12065 -0.305054)
			(stroke
				(width 0.1)
				(type default)
			)
			(layer "F.Fab")
		)
		(fp_line
			(start 0.67945 -0.3048)
			(end 0.67945 0.3048)
			(stroke
				(width 0.1)
				(type default)
			)
			(layer "F.Fab")
		)
		(fp_line
			(start 0.12065 -0.3048)
			(end 0.67945 -0.3048)
			(stroke
				(width 0.1)
				(type default)
			)
			(layer "F.Fab")
		)
		(fp_line
			(start 0.12065 -0.2794)
			(end 0.12065 -0.3048)
			(stroke
				(width 0.1)
				(type default)
			)
			(layer "F.Fab")
		)
		(fp_line
			(start -0.12065 -0.2794)
			(end 0.12065 -0.2794)
			(stroke
				(width 0.1)
				(type default)
			)
			(layer "F.Fab")
		)
		(fp_line
			(start 0.120396 0.2794)
			(end -0.12065 0.2794)
			(stroke
				(width 0.1)
				(type default)
			)
			(layer "F.Fab")
		)
		(fp_line
			(start -0.12065 0.2794)
			(end -0.12065 0.3048)
			(stroke
				(width 0.1)
				(type default)
			)
			(layer "F.Fab")
		)
		(fp_line
			(start 0.67945 0.3048)
			(end 0.120396 0.3048)
			(stroke
				(width 0.1)
				(type default)
			)
			(layer "F.Fab")
		)
		(fp_line
			(start 0.120396 0.3048)
			(end 0.120396 0.2794)
			(stroke
				(width 0.1)
				(type default)
			)
			(layer "F.Fab")
		)
		(fp_line
			(start -0.12065 0.3048)
			(end -0.67945 0.3048)
			(stroke
				(width 0.1)
				(type default)
			)
			(layer "F.Fab")
		)
		(fp_line
			(start -0.67945 0.3048)
			(end -0.67945 -0.305054)
			(stroke
				(width 0.1)
				(type default)
			)
			(layer "F.Fab")
		)
		(pad "1" smd circle
			(at -0.40005 0 90)
			(size 0 0)
			(layers "F.Cu" "F.Mask" "F.Paste")
			(net "FLASH_WP_STATUS_R1")
		)
		(pad "2" smd circle
			(at 0.40005 0 90)
			(size 0 0)
			(layers "F.Cu" "F.Mask" "F.Paste")
			(net "FLASH_WP_STATUS")
		)
	)
	(footprint ""
		(layer "F.Cu")
		(at 12.319 -84.328)
		(property "Reference" "R446"
			(at 0 0 0)
			(layer "F.SilkS")
			(hide yes)
			(effects
				(font
					(size 1.27 1.27)
				)
			)
		)
		(property "Value" ""
			(at 0 0 0)
			(layer "F.Fab")
			(effects
				(font
					(size 1.27 1.27)
				)
			)
		)
		(duplicate_pad_numbers_are_jumpers no)
		(fp_line
			(start -0.7874 -0.4064)
			(end 0.7874 -0.4064)
			(stroke
				(width 0.1524)
				(type default)
			)
			(layer "F.SilkS")
		)
		(fp_line
			(start -0.7874 0.4064)
			(end -0.7874 -0.4064)
			(stroke
				(width 0.1524)
				(type default)
			)
			(layer "F.SilkS")
		)
		(fp_line
			(start 0.7874 -0.4064)
			(end 0.7874 0.4064)
			(stroke
				(width 0.1524)
				(type default)
			)
			(layer "F.SilkS")
		)
		(fp_line
			(start 0.7874 0.4064)
			(end -0.7874 0.4064)
			(stroke
				(width 0.1524)
				(type default)
			)
			(layer "F.SilkS")
		)
		(fp_line
			(start -0.67945 -0.305054)
			(end -0.12065 -0.305054)
			(stroke
				(width 0.1)
				(type default)
			)
			(layer "F.Fab")
		)
		(fp_line
			(start -0.67945 0.3048)
			(end -0.67945 -0.305054)
			(stroke
				(width 0.1)
				(type default)
			)
			(layer "F.Fab")
		)
		(fp_line
			(start -0.12065 -0.305054)
			(end -0.12065 -0.2794)
			(stroke
				(width 0.1)
				(type default)
			)
			(layer "F.Fab")
		)
		(fp_line
			(start -0.12065 -0.2794)
			(end 0.12065 -0.2794)
			(stroke
				(width 0.1)
				(type default)
			)
			(layer "F.Fab")
		)
		(fp_line
			(start -0.12065 0.2794)
			(end -0.12065 0.3048)
			(stroke
				(width 0.1)
				(type default)
			)
			(layer "F.Fab")
		)
		(fp_line
			(start -0.12065 0.3048)
			(end -0.67945 0.3048)
			(stroke
				(width 0.1)
				(type default)
			)
			(layer "F.Fab")
		)
		(fp_line
			(start 0.120396 0.2794)
			(end -0.12065 0.2794)
			(stroke
				(width 0.1)
				(type default)
			)
			(layer "F.Fab")
		)
		(fp_line
			(start 0.120396 0.3048)
			(end 0.120396 0.2794)
			(stroke
				(width 0.1)
				(type default)
			)
			(layer "F.Fab")
		)
		(fp_line
			(start 0.12065 -0.3048)
			(end 0.67945 -0.3048)
			(stroke
				(width 0.1)
				(type default)
			)
			(layer "F.Fab")
		)
		(fp_line
			(start 0.12065 -0.2794)
			(end 0.12065 -0.3048)
			(stroke
				(width 0.1)
				(type default)
			)
			(layer "F.Fab")
		)
		(fp_line
			(start 0.67945 -0.3048)
			(end 0.67945 0.3048)
			(stroke
				(width 0.1)
				(type default)
			)
			(layer "F.Fab")
		)
		(fp_line
			(start 0.67945 0.3048)
			(end 0.120396 0.3048)
			(stroke
				(width 0.1)
				(type default)
			)
			(layer "F.Fab")
		)
		(pad "1" smd circle
			(at -0.40005 0)
			(size 0 0)
			(layers "F.Cu" "F.Mask" "F.Paste")
			(net "P3V3_AUX")
		)
		(pad "2" smd circle
			(at 0.40005 0)
			(size 0 0)
			(layers "F.Cu" "F.Mask" "F.Paste")
			(net "FM_PECI_SEL_N")
		)
	)
	(footprint ""
		(layer "F.Cu")
		(at 83.90001 -22.690074)
		(property "Reference" "H9"
			(at 3.474212 0.323596 0)
			(unlocked yes)
			(layer "F.SilkS")
			(effects
				(font
					(size 0.7874 0.5842)
					(thickness 0.1524)
				)
				(justify left)
			)
		)
		(property "Value" ""
			(at 0 0 0)
			(layer "F.Fab")
			(effects
				(font
					(size 1.27 1.27)
				)
			)
		)
		(duplicate_pad_numbers_are_jumpers no)
		(pad "1" thru_hole circle
			(at 0 0)
			(size 6.0452 6.0452)
			(drill 3.1496)
			(layers "*.Cu" "*.Mask")
			(remove_unused_layers no)
			(net "GND")
			(clearance -1.1938)
		)
	)
	(footprint ""
		(layer "F.Cu")
		(at 56.0324 -81.153 90)
		(property "Reference" "R551"
			(at 0 0 90)
			(layer "F.SilkS")
			(hide yes)
			(effects
				(font
					(size 1.27 1.27)
				)
			)
		)
		(property "Value" ""
			(at 0 0 90)
			(layer "F.Fab")
			(effects
				(font
					(size 1.27 1.27)
				)
			)
		)
		(duplicate_pad_numbers_are_jumpers no)
		(fp_line
			(start 0.7874 -0.4064)
			(end 0.7874 0.4064)
			(stroke
				(width 0.1524)
				(type default)
			)
			(layer "F.SilkS")
		)
		(fp_line
			(start -0.7874 -0.4064)
			(end 0.7874 -0.4064)
			(stroke
				(width 0.1524)
				(type default)
			)
			(layer "F.SilkS")
		)
		(fp_line
			(start 0.7874 0.4064)
			(end -0.7874 0.4064)
			(stroke
				(width 0.1524)
				(type default)
			)
			(layer "F.SilkS")
		)
		(fp_line
			(start -0.7874 0.4064)
			(end -0.7874 -0.4064)
			(stroke
				(width 0.1524)
				(type default)
			)
			(layer "F.SilkS")
		)
		(fp_line
			(start -0.12065 -0.305054)
			(end -0.12065 -0.2794)
			(stroke
				(width 0.1)
				(type default)
			)
			(layer "F.Fab")
		)
		(fp_line
			(start -0.67945 -0.305054)
			(end -0.12065 -0.305054)
			(stroke
				(width 0.1)
				(type default)
			)
			(layer "F.Fab")
		)
		(fp_line
			(start 0.67945 -0.3048)
			(end 0.67945 0.3048)
			(stroke
				(width 0.1)
				(type default)
			)
			(layer "F.Fab")
		)
		(fp_line
			(start 0.12065 -0.3048)
			(end 0.67945 -0.3048)
			(stroke
				(width 0.1)
				(type default)
			)
			(layer "F.Fab")
		)
		(fp_line
			(start 0.12065 -0.2794)
			(end 0.12065 -0.3048)
			(stroke
				(width 0.1)
				(type default)
			)
			(layer "F.Fab")
		)
		(fp_line
			(start -0.12065 -0.2794)
			(end 0.12065 -0.2794)
			(stroke
				(width 0.1)
				(type default)
			)
			(layer "F.Fab")
		)
		(fp_line
			(start 0.120396 0.2794)
			(end -0.12065 0.2794)
			(stroke
				(width 0.1)
				(type default)
			)
			(layer "F.Fab")
		)
		(fp_line
			(start -0.12065 0.2794)
			(end -0.12065 0.3048)
			(stroke
				(width 0.1)
				(type default)
			)
			(layer "F.Fab")
		)
		(fp_line
			(start 0.67945 0.3048)
			(end 0.120396 0.3048)
			(stroke
				(width 0.1)
				(type default)
			)
			(layer "F.Fab")
		)
		(fp_line
			(start 0.120396 0.3048)
			(end 0.120396 0.2794)
			(stroke
				(width 0.1)
				(type default)
			)
			(layer "F.Fab")
		)
		(fp_line
			(start -0.12065 0.3048)
			(end -0.67945 0.3048)
			(stroke
				(width 0.1)
				(type default)
			)
			(layer "F.Fab")
		)
		(fp_line
			(start -0.67945 0.3048)
			(end -0.67945 -0.305054)
			(stroke
				(width 0.1)
				(type default)
			)
			(layer "F.Fab")
		)
		(pad "1" smd circle
			(at -0.40005 0 90)
			(size 0 0)
			(layers "F.Cu" "F.Mask" "F.Paste")
			(net "FLASH_WP_STATUS")
		)
		(pad "2" smd circle
			(at 0.40005 0 90)
			(size 0 0)
			(layers "F.Cu" "F.Mask" "F.Paste")
			(net "FLASH_R_WP_STATUS")
		)
	)
	(footprint ""
		(layer "F.Cu")
		(at 36.1061 -47.13605 -90)
		(property "Reference" "R438"
			(at 0 0 270)
			(layer "F.SilkS")
			(hide yes)
			(effects
				(font
					(size 1.27 1.27)
				)
			)
		)
		(property "Value" ""
			(at 0 0 270)
			(layer "F.Fab")
			(effects
				(font
					(size 1.27 1.27)
				)
			)
		)
		(duplicate_pad_numbers_are_jumpers no)
		(fp_line
			(start -0.7874 0.4064)
			(end -0.7874 -0.4064)
			(stroke
				(width 0.1524)
				(type default)
			)
			(layer "F.SilkS")
		)
		(fp_line
			(start 0.7874 0.4064)
			(end -0.7874 0.4064)
			(stroke
				(width 0.1524)
				(type default)
			)
			(layer "F.SilkS")
		)
		(fp_line
			(start -0.7874 -0.4064)
			(end 0.7874 -0.4064)
			(stroke
				(width 0.1524)
				(type default)
			)
			(layer "F.SilkS")
		)
		(fp_line
			(start 0.7874 -0.4064)
			(end 0.7874 0.4064)
			(stroke
				(width 0.1524)
				(type default)
			)
			(layer "F.SilkS")
		)
		(fp_line
			(start -0.67945 0.3048)
			(end -0.67945 -0.305054)
			(stroke
				(width 0.1)
				(type default)
			)
			(layer "F.Fab")
		)
		(fp_line
			(start -0.12065 0.3048)
			(end -0.67945 0.3048)
			(stroke
				(width 0.1)
				(type default)
			)
			(layer "F.Fab")
		)
		(fp_line
			(start 0.120396 0.3048)
			(end 0.120396 0.2794)
			(stroke
				(width 0.1)
				(type default)
			)
			(layer "F.Fab")
		)
		(fp_line
			(start 0.67945 0.3048)
			(end 0.120396 0.3048)
			(stroke
				(width 0.1)
				(type default)
			)
			(layer "F.Fab")
		)
		(fp_line
			(start -0.12065 0.2794)
			(end -0.12065 0.3048)
			(stroke
				(width 0.1)
				(type default)
			)
			(layer "F.Fab")
		)
		(fp_line
			(start 0.120396 0.2794)
			(end -0.12065 0.2794)
			(stroke
				(width 0.1)
				(type default)
			)
			(layer "F.Fab")
		)
		(fp_line
			(start -0.12065 -0.2794)
			(end 0.12065 -0.2794)
			(stroke
				(width 0.1)
				(type default)
			)
			(layer "F.Fab")
		)
		(fp_line
			(start 0.12065 -0.2794)
			(end 0.12065 -0.3048)
			(stroke
				(width 0.1)
				(type default)
			)
			(layer "F.Fab")
		)
		(fp_line
			(start 0.12065 -0.3048)
			(end 0.67945 -0.3048)
			(stroke
				(width 0.1)
				(type default)
			)
			(layer "F.Fab")
		)
		(fp_line
			(start 0.67945 -0.3048)
			(end 0.67945 0.3048)
			(stroke
				(width 0.1)
				(type default)
			)
			(layer "F.Fab")
		)
		(fp_line
			(start -0.67945 -0.305054)
			(end -0.12065 -0.305054)
			(stroke
				(width 0.1)
				(type default)
			)
			(layer "F.Fab")
		)
		(fp_line
			(start -0.12065 -0.305054)
			(end -0.12065 -0.2794)
			(stroke
				(width 0.1)
				(type default)
			)
			(layer "F.Fab")
		)
		(pad "1" smd circle
			(at -0.40005 0 270)
			(size 0 0)
			(layers "F.Cu" "F.Mask" "F.Paste")
			(net "P3V3_AUX")
		)
		(pad "2" smd circle
			(at 0.40005 0 270)
			(size 0 0)
			(layers "F.Cu" "F.Mask" "F.Paste")
			(net "SMB_BMC_MM14_SDA")
		)
	)
)
